(kicad_pcb
	(version 20260206)
	(generator "pcbnew")
	(generator_version "10.0")
	(general
		(thickness 1.21888)
		(legacy_teardrops no)
	)
	(paper "A4")
	(title_block
		(title "timecard-v9 — TimeCard-DC-V9_EXP.PcbDoc")
		(comment 1 "Time Appliance Project (Time Card) / footprints 139-148 of 402")
	)
	(layers
		(0 "F.Cu" signal "TOP")
		(4 "In1.Cu" signal "SGND")
		(6 "In2.Cu" signal "IN1")
		(8 "In3.Cu" signal "IN2")
		(10 "In4.Cu" signal "SGND1")
		(2 "B.Cu" signal "BOTTOM")
		(9 "F.Adhes" user "F.Adhesive")
		(11 "B.Adhes" user "B.Adhesive")
		(13 "F.Paste" user "Top Paste")
		(15 "B.Paste" user "Bottom Paste")
		(5 "F.SilkS" user "Top Overlay")
		(7 "B.SilkS" user "Bottom Overlay")
		(1 "F.Mask" user "Top Solder")
		(3 "B.Mask" user "Bottom Solder")
		(17 "Dwgs.User" user "User.Drawings")
		(19 "Cmts.User" user "User.Comments")
		(21 "Eco1.User" user "User.Eco1")
		(23 "Eco2.User" user "User.Eco2")
		(25 "Edge.Cuts" user)
		(27 "Margin" user)
		(31 "F.CrtYd" user "Top Courtyard")
		(29 "B.CrtYd" user "Bottom Courtyard")
		(35 "F.Fab" user "Top Component Center")
		(33 "B.Fab" user "Bottom Component Center")
	)
	(footprint "Vault:FP-GRM31C-0_2-e0_3_0_8-IPC_C"
		(layer "F.Cu")
		(at 188.94582 86.9162)
		(property "Reference" "C77"
			(at 1.20438 -1.473069 0)
			(unlocked yes)
			(layer "F.SilkS")
			(effects
				(font
					(size 0.762 0.762)
					(thickness 0.2286)
				)
			)
		)
		(property "Value" "4.7uF_50V_1206"
			(at 8.594605 2.719551 0)
			(unlocked yes)
			(layer "F.SilkS")
			(hide yes)
			(effects
				(font
					(size 0.762 0.762)
					(thickness 0.2286)
				)
			)
		)
		(sheetname "03-POWER")
		(sheetfile "03-POWER.kicad_sch")
		(duplicate_pad_numbers_are_jumpers no)
		(fp_line
			(start -0.39847 -0.9)
			(end 0.39846 -0.9)
			(stroke
				(width 0.2)
				(type solid)
			)
			(layer "F.SilkS")
		)
		(fp_line
			(start -0.39847 0.9)
			(end 0.39846 0.9)
			(stroke
				(width 0.2)
				(type solid)
			)
			(layer "F.SilkS")
		)
		(fp_line
			(start -1.9531 -1)
			(end 1.9531 -1)
			(stroke
				(width 0.2)
				(type solid)
			)
			(layer "F.CrtYd")
		)
		(fp_line
			(start -1.9531 1)
			(end -1.9531 -1)
			(stroke
				(width 0.2)
				(type solid)
			)
			(layer "F.CrtYd")
		)
		(fp_line
			(start -1.9531 1)
			(end 1.9531 1)
			(stroke
				(width 0.2)
				(type solid)
			)
			(layer "F.CrtYd")
		)
		(fp_line
			(start 1.9531 1)
			(end 1.9531 -1)
			(stroke
				(width 0.2)
				(type solid)
			)
			(layer "F.CrtYd")
		)
		(fp_line
			(start -1.9531 -1)
			(end 1.9531 -1)
			(stroke
				(width 0.2)
				(type solid)
			)
			(layer "F.Fab")
		)
		(fp_line
			(start -1.9531 1)
			(end -1.9531 -1)
			(stroke
				(width 0.2)
				(type solid)
			)
			(layer "F.Fab")
		)
		(fp_line
			(start -1.9531 1)
			(end 1.9531 1)
			(stroke
				(width 0.2)
				(type solid)
			)
			(layer "F.Fab")
		)
		(fp_line
			(start -0.5 0)
			(end 0.5 0)
			(stroke
				(width 0.1)
				(type solid)
			)
			(layer "F.Fab")
		)
		(fp_line
			(start 0 0.5)
			(end 0 -0.5)
			(stroke
				(width 0.1)
				(type solid)
			)
			(layer "F.Fab")
		)
		(fp_line
			(start 1.9531 1)
			(end 1.9531 -1)
			(stroke
				(width 0.2)
				(type solid)
			)
			(layer "F.Fab")
		)
		(fp_text user "${REFERENCE}"
			(at -0.00001 0.09602 360)
			(unlocked yes)
			(layer "F.Fab")
			(effects
				(font
					(face "Arial")
					(size 0.63 0.63)
					(thickness 0.1)
				)
				(justify left bottom)
			)
		)
		(pad "1" smd rect
			(at -1.27578 0)
			(size 1.15464 1.7062)
			(layers "F.Cu" "F.Mask" "F.Paste")
			(net "+12V")
			(solder_mask_margin 0)
			(solder_paste_margin 0)
		)
		(pad "2" smd rect
			(at 1.27578 0)
			(size 1.15464 1.7062)
			(layers "F.Cu" "F.Mask" "F.Paste")
			(net "GND")
			(solder_mask_margin 0)
			(solder_paste_margin 0)
		)
	)
	(footprint "Vault:RESC1005X40X25NL05T05"
		(layer "F.Cu")
		(at 160.9716 130.3162 180)
		(property "Reference" "R86"
			(at -0.5786 -1.126921 0)
			(unlocked yes)
			(layer "F.SilkS")
			(effects
				(font
					(size 0.762 0.762)
					(thickness 0.2286)
				)
			)
		)
		(property "Value" "27_1%_0402"
			(at -2.732271 7.37632 90)
			(unlocked yes)
			(layer "F.SilkS")
			(hide yes)
			(effects
				(font
					(size 0.762 0.762)
					(thickness 0.2286)
				)
			)
		)
		(sheetname "09-USBUart_PPSMUX_UARTMUX")
		(sheetfile "09-USBUart_PPSMUX_UARTMUX.kicad_sch")
		(duplicate_pad_numbers_are_jumpers no)
		(pad "1" smd rect
			(at -0.45 0 270)
			(size 0.55 0.55)
			(layers "F.Cu" "F.Mask" "F.Paste")
			(net "GND")
		)
		(pad "2" smd rect
			(at 0.45 0 270)
			(size 0.55 0.55)
			(layers "F.Cu" "F.Mask" "F.Paste")
			(net "NetR86_2")
		)
	)
	(footprint "Vault:FP-D0008A-MFG"
		(layer "F.Cu")
		(at 168.78957 91.9162 90)
		(property "Reference" "U19"
			(at -0.2286 3.373069 270)
			(unlocked yes)
			(layer "F.SilkS")
			(effects
				(font
					(size 0.762 0.762)
					(thickness 0.2286)
				)
			)
		)
		(property "Value" "INA219BIDR"
			(at 3.16004 4.408671 90)
			(unlocked yes)
			(layer "F.SilkS")
			(hide yes)
			(effects
				(font
					(size 0.762 0.762)
					(thickness 0.2286)
				)
			)
		)
		(sheetname "03-POWER")
		(sheetfile "03-POWER.kicad_sch")
		(duplicate_pad_numbers_are_jumpers no)
		(fp_line
			(start 1.5 -2.5)
			(end 1.5 2.5)
			(stroke
				(width 0.2)
				(type solid)
			)
			(layer "F.SilkS")
		)
		(fp_line
			(start -1.5 -2.5)
			(end 1.5 -2.5)
			(stroke
				(width 0.2)
				(type solid)
			)
			(layer "F.SilkS")
		)
		(fp_line
			(start -1.5 -2.5)
			(end -1.5 2.5)
			(stroke
				(width 0.2)
				(type solid)
			)
			(layer "F.SilkS")
		)
		(fp_line
			(start -1.5 2.5)
			(end 1.5 2.5)
			(stroke
				(width 0.2)
				(type solid)
			)
			(layer "F.SilkS")
		)
		(fp_circle
			(center -4.05 -1.905)
			(end -3.925 -1.905)
			(stroke
				(width 0.25)
				(type solid)
			)
			(fill no)
			(layer "F.SilkS")
		)
		(fp_circle
			(center -0.725 -1.725)
			(end -0.475 -1.725)
			(stroke
				(width 0.5)
				(type solid)
			)
			(fill no)
			(layer "F.SilkS")
		)
		(fp_line
			(start 3.575 -2.75)
			(end 3.575 2.75)
			(stroke
				(width 0.2)
				(type solid)
			)
			(layer "F.CrtYd")
		)
		(fp_line
			(start -3.575 -2.75)
			(end 3.575 -2.75)
			(stroke
				(width 0.2)
				(type solid)
			)
			(layer "F.CrtYd")
		)
		(fp_line
			(start -3.575 -2.75)
			(end -3.575 2.75)
			(stroke
				(width 0.2)
				(type solid)
			)
			(layer "F.CrtYd")
		)
		(fp_line
			(start -3.575 2.75)
			(end 3.575 2.75)
			(stroke
				(width 0.2)
				(type solid)
			)
			(layer "F.CrtYd")
		)
		(fp_line
			(start 3.575 -2.75)
			(end 3.575 2.75)
			(stroke
				(width 0.2)
				(type solid)
			)
			(layer "F.Fab")
		)
		(fp_line
			(start -3.575 -2.75)
			(end 3.575 -2.75)
			(stroke
				(width 0.2)
				(type solid)
			)
			(layer "F.Fab")
		)
		(fp_line
			(start -3.575 -2.75)
			(end -3.575 2.75)
			(stroke
				(width 0.2)
				(type solid)
			)
			(layer "F.Fab")
		)
		(fp_line
			(start 0 -0.5)
			(end 0 0.5)
			(stroke
				(width 0.1)
				(type solid)
			)
			(layer "F.Fab")
		)
		(fp_line
			(start -0.5 0)
			(end 0.5 0)
			(stroke
				(width 0.1)
				(type solid)
			)
			(layer "F.Fab")
		)
		(fp_line
			(start -3.575 2.75)
			(end 3.575 2.75)
			(stroke
				(width 0.2)
				(type solid)
			)
			(layer "F.Fab")
		)
		(fp_text user "${REFERENCE}"
			(at -0.00001 0.09602 90)
			(unlocked yes)
			(layer "F.Fab")
			(effects
				(font
					(face "Arial")
					(size 0.63 0.63)
					(thickness 0.1)
				)
				(justify left bottom)
			)
		)
		(pad "1" smd roundrect
			(at -2.7 -1.905 90)
			(size 1.55 0.6)
			(layers "F.Cu" "F.Mask" "F.Paste")
			(roundrect_rratio 0.085)
			(net "NetR80_1")
			(solder_mask_margin 0)
			(solder_paste_margin 0)
		)
		(pad "2" smd roundrect
			(at -2.7 -0.635 90)
			(size 1.55 0.6)
			(layers "F.Cu" "F.Mask" "F.Paste")
			(roundrect_rratio 0.085)
			(net "NetR79_1")
			(solder_mask_margin 0)
			(solder_paste_margin 0)
		)
		(pad "3" smd roundrect
			(at -2.7 0.635 90)
			(size 1.55 0.6)
			(layers "F.Cu" "F.Mask" "F.Paste")
			(roundrect_rratio 0.085)
			(net "SENS_I2C_SDA")
			(solder_mask_margin 0)
			(solder_paste_margin 0)
		)
		(pad "4" smd roundrect
			(at -2.7 1.905 90)
			(size 1.55 0.6)
			(layers "F.Cu" "F.Mask" "F.Paste")
			(roundrect_rratio 0.085)
			(net "SENS_I2C_SCL")
			(solder_mask_margin 0)
			(solder_paste_margin 0)
		)
		(pad "5" smd roundrect
			(at 2.7 1.905 90)
			(size 1.55 0.6)
			(layers "F.Cu" "F.Mask" "F.Paste")
			(roundrect_rratio 0.085)
			(net "+3.3V")
			(solder_mask_margin 0)
			(solder_paste_margin 0)
		)
		(pad "6" smd roundrect
			(at 2.7 0.635 90)
			(size 1.55 0.6)
			(layers "F.Cu" "F.Mask" "F.Paste")
			(roundrect_rratio 0.085)
			(net "GND")
			(solder_mask_margin 0)
			(solder_paste_margin 0)
		)
		(pad "7" smd roundrect
			(at 2.7 -0.635 90)
			(size 1.55 0.6)
			(layers "F.Cu" "F.Mask" "F.Paste")
			(roundrect_rratio 0.085)
			(net "+3.3V")
			(solder_mask_margin 0)
			(solder_paste_margin 0)
		)
		(pad "8" smd roundrect
			(at 2.7 -1.905 90)
			(size 1.55 0.6)
			(layers "F.Cu" "F.Mask" "F.Paste")
			(roundrect_rratio 0.085)
			(net "P3V3_SENSE")
			(solder_mask_margin 0)
			(solder_paste_margin 0)
		)
	)
	(footprint "Vault:RESC1608X55X25NL10T15"
		(layer "F.Cu")
		(at 75.1216 126.4162 180)
		(property "Reference" "R28"
			(at 0.7 0.953785 0)
			(unlocked yes)
			(layer "F.SilkS")
			(effects
				(font
					(size 0.762 0.762)
					(thickness 0.2286)
				)
				(justify left bottom)
			)
		)
		(property "Value" "49.9R"
			(at 1.1445 -4.336645 0)
			(unlocked yes)
			(layer "F.SilkS")
			(hide yes)
			(effects
				(font
					(size 0.762 0.762)
					(thickness 0.2286)
				)
				(justify left bottom)
			)
		)
		(sheetname "01-USER_IO")
		(sheetfile "01-USER_IO.kicad_sch")
		(duplicate_pad_numbers_are_jumpers no)
		(pad "1" smd rect
			(at -0.7 0 270)
			(size 0.9 0.7)
			(layers "F.Cu" "F.Mask" "F.Paste")
			(net "NetR28_1")
		)
		(pad "2" smd rect
			(at 0.7 0 270)
			(size 0.9 0.7)
			(layers "F.Cu" "F.Mask" "F.Paste")
			(net "NetAN3_1")
		)
	)
	(footprint "Vault:RESC1005X40X25NL05T05"
		(layer "F.Cu")
		(at 157.6216 116.8162 180)
		(property "Reference" "R95"
			(at -3.0286 -0.126931 0)
			(unlocked yes)
			(layer "F.SilkS")
			(effects
				(font
					(size 0.762 0.762)
					(thickness 0.2286)
				)
			)
		)
		(property "Value" "27_1%_0402"
			(at -2.935471 7.78247 90)
			(unlocked yes)
			(layer "F.SilkS")
			(hide yes)
			(effects
				(font
					(size 0.762 0.762)
					(thickness 0.2286)
				)
			)
		)
		(sheetname "08-DIPSwitches_I2C")
		(sheetfile "08-DIPSwitches_I2C.kicad_sch")
		(duplicate_pad_numbers_are_jumpers no)
		(pad "1" smd rect
			(at -0.45 0 270)
			(size 0.55 0.55)
			(layers "F.Cu" "F.Mask" "F.Paste")
			(net "MAC_I2C_SDA")
		)
		(pad "2" smd rect
			(at 0.45 0 270)
			(size 0.55 0.55)
			(layers "F.Cu" "F.Mask" "F.Paste")
			(net "NetR95_2")
		)
	)
	(footprint "Vault:61300411121"
		(layer "F.Cu")
		(at 153.7216 90.8462 90)
		(property "Reference" "P5"
			(at 6.945129 0.164685 0)
			(unlocked yes)
			(layer "F.SilkS")
			(effects
				(font
					(size 0.762 0.762)
					(thickness 0.2032)
				)
			)
		)
		(property "Value" "61300411121"
			(at -6.999471 6.25871 0)
			(unlocked yes)
			(layer "F.SilkS")
			(hide yes)
			(effects
				(font
					(size 0.762 0.762)
					(thickness 0.2032)
				)
			)
		)
		(sheetname "05-GPS_IMU_SENSORS")
		(sheetfile "05-GPS_IMU_SENSORS.kicad_sch")
		(duplicate_pad_numbers_are_jumpers no)
		(fp_line
			(start 5.23 -1.345)
			(end 5.23 1.345)
			(stroke
				(width 0.2)
				(type solid)
			)
			(layer "F.SilkS")
		)
		(fp_line
			(start -5.23 -1.345)
			(end 5.23 -1.345)
			(stroke
				(width 0.2)
				(type solid)
			)
			(layer "F.SilkS")
		)
		(fp_line
			(start -5.23 -1.345)
			(end -5.23 1.345)
			(stroke
				(width 0.2)
				(type solid)
			)
			(layer "F.SilkS")
		)
		(fp_line
			(start -5.23 1.345)
			(end 5.23 1.345)
			(stroke
				(width 0.2)
				(type solid)
			)
			(layer "F.SilkS")
		)
		(pad "1" thru_hole rect
			(at -3.81 0 90)
			(size 1.6 1.6)
			(drill 1.1)
			(layers "*.Cu" "*.Mask")
			(remove_unused_layers no)
			(net "+3.3V")
		)
		(pad "2" thru_hole circle
			(at -1.27 0 90)
			(size 1.6 1.6)
			(drill 1.1)
			(layers "*.Cu" "*.Mask")
			(remove_unused_layers no)
			(net "GND")
			(thermal_bridge_angle 90)
		)
		(pad "3" thru_hole circle
			(at 1.27 0 90)
			(size 1.6 1.6)
			(drill 1.1)
			(layers "*.Cu" "*.Mask")
			(remove_unused_layers no)
			(net "DC_I2C_SCL")
			(thermal_bridge_angle 90)
		)
		(pad "4" thru_hole circle
			(at 3.81 0 90)
			(size 1.6 1.6)
			(drill 1.1)
			(layers "*.Cu" "*.Mask")
			(remove_unused_layers no)
			(net "DC_I2C_SDA")
			(thermal_bridge_angle 90)
		)
	)
	(footprint "Vault:RESC1608X55X30NL15T15"
		(layer "F.Cu")
		(at 87.70686 89.06371)
		(property "Reference" "R41"
			(at -2.521395 0.026921 0)
			(unlocked yes)
			(layer "F.SilkS")
			(effects
				(font
					(size 0.762 0.762)
					(thickness 0.2286)
				)
			)
		)
		(property "Value" "4.7K"
			(at 1.61204 2.325871 0)
			(unlocked yes)
			(layer "F.SilkS")
			(hide yes)
			(effects
				(font
					(size 0.762 0.762)
					(thickness 0.2286)
				)
			)
		)
		(sheetname "02-USER_IO_STATUS")
		(sheetfile "02-USER_IO_STATUS.kicad_sch")
		(duplicate_pad_numbers_are_jumpers no)
		(pad "1" smd rect
			(at -0.75 0 90)
			(size 0.95 0.95)
			(layers "F.Cu" "F.Mask" "F.Paste")
			(net "GND")
		)
		(pad "2" smd rect
			(at 0.75 0 90)
			(size 0.95 0.95)
			(layers "F.Cu" "F.Mask" "F.Paste")
			(net "NetR41_2")
		)
	)
	(footprint "SA53:SolderSocket"
		(locked yes)
		(layer "F.Cu")
		(at 86.9216 137.3162 90)
		(property "Reference" "SKT5"
			(at -6.626931 0.3286 0)
			(unlocked yes)
			(layer "F.SilkS")
			(effects
				(font
					(size 0.762 0.762)
					(thickness 0.2286)
				)
			)
		)
		(property "Value" "0332-0-43-80-18-27-10-0"
			(at -2.910071 16.1362 0)
			(unlocked yes)
			(layer "F.SilkS")
			(hide yes)
			(effects
				(font
					(size 0.762 0.762)
					(thickness 0.2286)
				)
			)
		)
		(sheetname "06-MAC")
		(sheetfile "06-MAC.kicad_sch")
		(duplicate_pad_numbers_are_jumpers no)
		(pad "1" thru_hole circle
			(at 0 0 90)
			(size 2.54 2.54)
			(drill 2.0066)
			(layers "*.Cu" "*.Mask")
			(remove_unused_layers no)
			(net "MAC_RF_OUT")
			(thermal_bridge_angle 90)
		)
	)
	(footprint "Vault:FP-39-30-0040-MFG"
		(layer "F.Cu")
		(at 225.5654 55.3207 90)
		(property "Reference" "J38"
			(at 4.711155 -10.3438 0)
			(unlocked yes)
			(layer "F.SilkS")
			(effects
				(font
					(size 0.762 0.762)
					(thickness 0.2286)
				)
				(justify left bottom)
			)
		)
		(property "Value" "39-30-0040"
			(at -20.802445 -1.5141 0)
			(unlocked yes)
			(layer "F.SilkS")
			(hide yes)
			(effects
				(font
					(size 0.762 0.762)
					(thickness 0.2286)
				)
				(justify left bottom)
			)
		)
		(sheetname "03-POWER")
		(sheetfile "03-POWER.kicad_sch")
		(duplicate_pad_numbers_are_jumpers no)
		(fp_line
			(start 5.0165 -6.35)
			(end 5.0165 6.731)
			(stroke
				(width 0.2)
				(type solid)
			)
			(layer "F.SilkS")
		)
		(fp_line
			(start 3.8455 -6.35)
			(end 5.0165 -6.35)
			(stroke
				(width 0.2)
				(type solid)
			)
			(layer "F.SilkS")
		)
		(fp_line
			(start -0.3455 -6.35)
			(end 0.3455 -6.35)
			(stroke
				(width 0.2)
				(type solid)
			)
			(layer "F.SilkS")
		)
		(fp_line
			(start -5.0165 -6.35)
			(end -3.8455 -6.35)
			(stroke
				(width 0.2)
				(type solid)
			)
			(layer "F.SilkS")
		)
		(fp_line
			(start -5.0165 -6.35)
			(end -5.0165 6.731)
			(stroke
				(width 0.2)
				(type solid)
			)
			(layer "F.SilkS")
		)
		(fp_line
			(start -5.0165 6.731)
			(end 5.0165 6.731)
			(stroke
				(width 0.2)
				(type solid)
			)
			(layer "F.SilkS")
		)
		(fp_circle
			(center 5.0045 -7.2438)
			(end 5.1295 -7.2438)
			(stroke
				(width 0.25)
				(type solid)
			)
			(fill no)
			(layer "F.SilkS")
		)
		(fp_line
			(start 5.1165 -14.5306)
			(end 5.1165 6.831)
			(stroke
				(width 0.2)
				(type solid)
			)
			(layer "F.CrtYd")
		)
		(fp_line
			(start -5.1165 -14.5306)
			(end 5.1165 -14.5306)
			(stroke
				(width 0.2)
				(type solid)
			)
			(layer "F.CrtYd")
		)
		(fp_line
			(start -5.1165 -14.5306)
			(end -5.1165 6.831)
			(stroke
				(width 0.2)
				(type solid)
			)
			(layer "F.CrtYd")
		)
		(fp_line
			(start -5.1165 6.831)
			(end 5.1165 6.831)
			(stroke
				(width 0.2)
				(type solid)
			)
			(layer "F.CrtYd")
		)
		(fp_line
			(start 5.1165 -14.5306)
			(end 5.1165 6.831)
			(stroke
				(width 0.2)
				(type solid)
			)
			(layer "F.Fab")
		)
		(fp_line
			(start -5.1165 -14.5306)
			(end 5.1165 -14.5306)
			(stroke
				(width 0.2)
				(type solid)
			)
			(layer "F.Fab")
		)
		(fp_line
			(start -5.1165 -14.5306)
			(end -5.1165 6.831)
			(stroke
				(width 0.2)
				(type solid)
			)
			(layer "F.Fab")
		)
		(fp_line
			(start 0 -0.5)
			(end 0 0.5)
			(stroke
				(width 0.1)
				(type solid)
			)
			(layer "F.Fab")
		)
		(fp_line
			(start -0.5 0)
			(end 0.5 0)
			(stroke
				(width 0.1)
				(type solid)
			)
			(layer "F.Fab")
		)
		(fp_line
			(start -5.1165 6.831)
			(end 5.1165 6.831)
			(stroke
				(width 0.2)
				(type solid)
			)
			(layer "F.Fab")
		)
		(fp_text user "${REFERENCE}"
			(at -0.00185 -3.56555 90)
			(unlocked yes)
			(layer "F.Fab")
			(effects
				(font
					(face "Arial")
					(size 0.63 0.63)
					(thickness 0.1)
				)
				(justify left bottom)
			)
		)
		(pad "" np_thru_hole circle
			(at 0 -0.254 90)
			(size 2.9972 2.9972)
			(drill 2.9972)
			(layers "*.Cu" "*.Mask")
			(solder_mask_margin 0)
			(solder_paste_margin -1000)
			(thermal_bridge_angle 90)
		)
		(pad "1" thru_hole rect
			(at 2.0955 -7.5438 90)
			(size 2.75 2.75)
			(drill 1.8)
			(layers "*.Cu" "*.Mask")
			(remove_unused_layers no)
			(net "GND")
			(solder_mask_margin 0)
			(solder_paste_margin -1000)
		)
		(pad "2" thru_hole circle
			(at -2.0955 -7.5438 90)
			(size 2.75 2.75)
			(drill 1.8)
			(layers "*.Cu" "*.Mask")
			(remove_unused_layers no)
			(net "GND")
			(solder_mask_margin 0)
			(solder_paste_margin -1000)
			(thermal_bridge_angle 90)
		)
		(pad "3" thru_hole circle
			(at 2.0955 -13.0556 90)
			(size 2.75 2.75)
			(drill 1.8)
			(layers "*.Cu" "*.Mask")
			(remove_unused_layers no)
			(net "NetCR1_1")
			(solder_mask_margin 0)
			(solder_paste_margin -1000)
			(thermal_bridge_angle 90)
		)
		(pad "4" thru_hole circle
			(at -2.0955 -13.0556 90)
			(size 2.75 2.75)
			(drill 1.8)
			(layers "*.Cu" "*.Mask")
			(remove_unused_layers no)
			(net "NetCR1_1")
			(solder_mask_margin 0)
			(solder_paste_margin -1000)
			(thermal_bridge_angle 90)
		)
	)
	(footprint "Vault:RESC1005X40X25NL05T05"
		(layer "F.Cu")
		(at 192.0216 135.2162 180)
		(property "Reference" "R149"
			(at -0.8936 -0.890901 0)
			(unlocked yes)
			(layer "F.SilkS")
			(effects
				(font
					(size 0.762 0.762)
					(thickness 0.2032)
				)
			)
		)
		(property "Value" "DNI_27_1%_0402"
			(at -2.732271 10.270975 90)
			(unlocked yes)
			(layer "F.SilkS")
			(hide yes)
			(effects
				(font
					(size 0.762 0.762)
					(thickness 0.2032)
				)
			)
		)
		(sheetname "11-M2_RCB_MUX")
		(sheetfile "11-M2_RCB_MUX.kicad_sch")
		(duplicate_pad_numbers_are_jumpers no)
		(pad "1" smd rect
			(at -0.45 0 270)
			(size 0.55 0.55)
			(layers "F.Cu" "F.Mask" "F.Paste")
			(net "RCB_GPS2_RX")
		)
		(pad "2" smd rect
			(at 0.45 0 270)
			(size 0.55 0.55)
			(layers "F.Cu" "F.Mask" "F.Paste")
			(net "GPS2_RX")
		)
	)
)
